(kicad_pcb
	(version 20260206)
	(generator "pcbnew")
	(generator_version "10.0")
	(general
		(thickness 1.6)
		(legacy_teardrops no)
	)
	(paper "A4")
	(title_block
		(title "03242023_DA0F0TMBIJ0_F0T_Motherboard_J_brd_V01_OCP.brd")
		(comment 1 "Grand Teton / footprints 5362-5367 of 6105")
	)
	(layers
		(0 "F.Cu" signal "TOP")
		(4 "In1.Cu" signal "GND")
		(6 "In2.Cu" signal "IN1")
		(8 "In3.Cu" signal "GND1")
		(10 "In4.Cu" signal "IN2")
		(12 "In5.Cu" signal "GND2")
		(14 "In6.Cu" signal "IN3")
		(16 "In7.Cu" signal "GND3")
		(18 "In8.Cu" signal "VCC")
		(20 "In9.Cu" signal "VCC1")
		(22 "In10.Cu" signal "GND4")
		(24 "In11.Cu" signal "IN4")
		(26 "In12.Cu" signal "GND5")
		(28 "In13.Cu" signal "IN5")
		(30 "In14.Cu" signal "GND6")
		(32 "In15.Cu" signal "IN6")
		(34 "In16.Cu" signal "GND7")
		(2 "B.Cu" signal "BOTTOM")
		(9 "F.Adhes" user "F.Adhesive")
		(11 "B.Adhes" user "B.Adhesive")
		(13 "F.Paste" user "Package Geometry/Pastemask Top")
		(15 "B.Paste" user "Package Geometry/Pastemask Bottom")
		(5 "F.SilkS" user "Ref Des/Silkscreen Top")
		(7 "B.SilkS" user "Ref Des/Silkscreen Bottom")
		(1 "F.Mask" user "Board Geometry/Soldermask Top")
		(3 "B.Mask" user "Board Geometry/Soldermask Bottom")
		(17 "Dwgs.User" user "User.Drawings")
		(19 "Cmts.User" user "User.Comments")
		(21 "Eco1.User" user "User.Eco1")
		(23 "Eco2.User" user "User.Eco2")
		(25 "Edge.Cuts" user "Board Geometry/Outline")
		(27 "Margin" user)
		(31 "F.CrtYd" user "Package Geometry/Place Bound Top")
		(29 "B.CrtYd" user "Package Geometry/Place Bound Bottom")
		(35 "F.Fab" user "Ref Des/Assembly Top")
		(33 "B.Fab" user "Ref Des/Assembly Bottom")
	)
	(footprint ""
		(layer "B.Cu")
		(at 102.845616 -360.296968 180)
		(property "Reference" "R2522"
			(at 0 0 0)
			(layer "B.SilkS")
			(hide yes)
			(effects
				(font
					(size 1.27 1.27)
				)
				(justify mirror)
			)
		)
		(property "Value" ""
			(at 0 0 0)
			(layer "B.Fab")
			(effects
				(font
					(size 1.27 1.27)
				)
				(justify mirror)
			)
		)
		(duplicate_pad_numbers_are_jumpers no)
		(fp_line
			(start 0.7874 0.4064)
			(end 0.7874 -0.4064)
			(stroke
				(width 0.1524)
				(type default)
			)
			(layer "B.SilkS")
		)
		(fp_line
			(start 0.7874 -0.4064)
			(end -0.7874 -0.4064)
			(stroke
				(width 0.1524)
				(type default)
			)
			(layer "B.SilkS")
		)
		(fp_line
			(start -0.7874 0.4064)
			(end 0.7874 0.4064)
			(stroke
				(width 0.1524)
				(type default)
			)
			(layer "B.SilkS")
		)
		(fp_line
			(start -0.7874 -0.4064)
			(end -0.7874 0.4064)
			(stroke
				(width 0.1524)
				(type default)
			)
			(layer "B.SilkS")
		)
		(fp_line
			(start 0.67945 0.3048)
			(end 0.67945 -0.305054)
			(stroke
				(width 0.1)
				(type default)
			)
			(layer "B.Fab")
		)
		(fp_line
			(start 0.67945 -0.305054)
			(end 0.12065 -0.305054)
			(stroke
				(width 0.1)
				(type default)
			)
			(layer "B.Fab")
		)
		(fp_line
			(start 0.12065 0.3048)
			(end 0.67945 0.3048)
			(stroke
				(width 0.1)
				(type default)
			)
			(layer "B.Fab")
		)
		(fp_line
			(start 0.12065 0.2794)
			(end 0.12065 0.3048)
			(stroke
				(width 0.1)
				(type default)
			)
			(layer "B.Fab")
		)
		(fp_line
			(start 0.12065 -0.2794)
			(end -0.12065 -0.2794)
			(stroke
				(width 0.1)
				(type default)
			)
			(layer "B.Fab")
		)
		(fp_line
			(start 0.12065 -0.305054)
			(end 0.12065 -0.2794)
			(stroke
				(width 0.1)
				(type default)
			)
			(layer "B.Fab")
		)
		(fp_line
			(start -0.120396 0.3048)
			(end -0.120396 0.2794)
			(stroke
				(width 0.1)
				(type default)
			)
			(layer "B.Fab")
		)
		(fp_line
			(start -0.120396 0.2794)
			(end 0.12065 0.2794)
			(stroke
				(width 0.1)
				(type default)
			)
			(layer "B.Fab")
		)
		(fp_line
			(start -0.12065 -0.2794)
			(end -0.12065 -0.3048)
			(stroke
				(width 0.1)
				(type default)
			)
			(layer "B.Fab")
		)
		(fp_line
			(start -0.12065 -0.3048)
			(end -0.67945 -0.3048)
			(stroke
				(width 0.1)
				(type default)
			)
			(layer "B.Fab")
		)
		(fp_line
			(start -0.67945 0.3048)
			(end -0.120396 0.3048)
			(stroke
				(width 0.1)
				(type default)
			)
			(layer "B.Fab")
		)
		(fp_line
			(start -0.67945 -0.3048)
			(end -0.67945 0.3048)
			(stroke
				(width 0.1)
				(type default)
			)
			(layer "B.Fab")
		)
		(pad "1" smd circle
			(at 0.40005 0)
			(size 0 0)
			(layers "B.Cu" "B.Mask" "B.Paste")
			(net "P3V3_AUX")
		)
		(pad "2" smd circle
			(at -0.40005 0)
			(size 0 0)
			(layers "B.Cu" "B.Mask" "B.Paste")
			(net "IRQ_PVCCIN_CPU1_VRHOT_R_N")
		)
	)
	(footprint ""
		(layer "B.Cu")
		(at 307.16601 -317.306452 90)
		(property "Reference" "C5"
			(at 0 0 90)
			(layer "B.SilkS")
			(hide yes)
			(effects
				(font
					(size 1.27 1.27)
				)
				(justify mirror)
			)
		)
		(property "Value" ""
			(at 0 0 90)
			(layer "B.Fab")
			(effects
				(font
					(size 1.27 1.27)
				)
				(justify mirror)
			)
		)
		(duplicate_pad_numbers_are_jumpers no)
		(fp_line
			(start 0.7874 -0.4064)
			(end -0.7874 -0.4064)
			(stroke
				(width 0.1524)
				(type default)
			)
			(layer "B.SilkS")
		)
		(fp_line
			(start -0.7874 -0.4064)
			(end -0.7874 0.4064)
			(stroke
				(width 0.1524)
				(type default)
			)
			(layer "B.SilkS")
		)
		(fp_line
			(start 0.7874 0.4064)
			(end 0.7874 -0.4064)
			(stroke
				(width 0.1524)
				(type default)
			)
			(layer "B.SilkS")
		)
		(fp_line
			(start -0.7874 0.4064)
			(end 0.7874 0.4064)
			(stroke
				(width 0.1524)
				(type default)
			)
			(layer "B.SilkS")
		)
		(fp_line
			(start 0.67945 -0.305054)
			(end 0.12065 -0.305054)
			(stroke
				(width 0.1)
				(type default)
			)
			(layer "B.Fab")
		)
		(fp_line
			(start 0.12065 -0.305054)
			(end 0.12065 -0.2794)
			(stroke
				(width 0.1)
				(type default)
			)
			(layer "B.Fab")
		)
		(fp_line
			(start -0.12065 -0.3048)
			(end -0.67945 -0.3048)
			(stroke
				(width 0.1)
				(type default)
			)
			(layer "B.Fab")
		)
		(fp_line
			(start -0.67945 -0.3048)
			(end -0.67945 0.3048)
			(stroke
				(width 0.1)
				(type default)
			)
			(layer "B.Fab")
		)
		(fp_line
			(start 0.12065 -0.2794)
			(end -0.12065 -0.2794)
			(stroke
				(width 0.1)
				(type default)
			)
			(layer "B.Fab")
		)
		(fp_line
			(start -0.12065 -0.2794)
			(end -0.12065 -0.3048)
			(stroke
				(width 0.1)
				(type default)
			)
			(layer "B.Fab")
		)
		(fp_line
			(start 0.12065 0.2794)
			(end 0.12065 0.3048)
			(stroke
				(width 0.1)
				(type default)
			)
			(layer "B.Fab")
		)
		(fp_line
			(start -0.120396 0.2794)
			(end 0.12065 0.2794)
			(stroke
				(width 0.1)
				(type default)
			)
			(layer "B.Fab")
		)
		(fp_line
			(start 0.67945 0.3048)
			(end 0.67945 -0.305054)
			(stroke
				(width 0.1)
				(type default)
			)
			(layer "B.Fab")
		)
		(fp_line
			(start 0.12065 0.3048)
			(end 0.67945 0.3048)
			(stroke
				(width 0.1)
				(type default)
			)
			(layer "B.Fab")
		)
		(fp_line
			(start -0.120396 0.3048)
			(end -0.120396 0.2794)
			(stroke
				(width 0.1)
				(type default)
			)
			(layer "B.Fab")
		)
		(fp_line
			(start -0.67945 0.3048)
			(end -0.120396 0.3048)
			(stroke
				(width 0.1)
				(type default)
			)
			(layer "B.Fab")
		)
		(pad "1" smd circle
			(at 0.40005 0 270)
			(size 0 0)
			(layers "B.Cu" "B.Mask" "B.Paste")
			(net "P3V3_AUX")
		)
		(pad "2" smd circle
			(at -0.40005 0 270)
			(size 0 0)
			(layers "B.Cu" "B.Mask" "B.Paste")
			(net "GND")
		)
	)
	(footprint ""
		(layer "B.Cu")
		(at 351.928938 -241.19967 90)
		(property "Reference" "C518"
			(at 0 0 90)
			(layer "B.SilkS")
			(hide yes)
			(effects
				(font
					(size 1.27 1.27)
				)
				(justify mirror)
			)
		)
		(property "Value" ""
			(at 0 0 90)
			(layer "B.Fab")
			(effects
				(font
					(size 1.27 1.27)
				)
				(justify mirror)
			)
		)
		(duplicate_pad_numbers_are_jumpers no)
		(fp_line
			(start 1.524 -0.762)
			(end -1.524 -0.762)
			(stroke
				(width 0.1524)
				(type default)
			)
			(layer "B.SilkS")
		)
		(fp_line
			(start -1.524 -0.762)
			(end -1.524 0.762)
			(stroke
				(width 0.1524)
				(type default)
			)
			(layer "B.SilkS")
		)
		(fp_line
			(start 1.524 0.762)
			(end 1.524 -0.762)
			(stroke
				(width 0.1524)
				(type default)
			)
			(layer "B.SilkS")
		)
		(fp_line
			(start -1.524 0.762)
			(end 1.524 0.762)
			(stroke
				(width 0.1524)
				(type default)
			)
			(layer "B.SilkS")
		)
		(fp_line
			(start 1.1049 -0.724916)
			(end 1.1049 0.724916)
			(stroke
				(width 0.1)
				(type default)
			)
			(layer "B.Fab")
		)
		(fp_line
			(start -1.1049 -0.724916)
			(end 1.1049 -0.724916)
			(stroke
				(width 0.1)
				(type default)
			)
			(layer "B.Fab")
		)
		(fp_line
			(start 1.1049 0.724916)
			(end -1.1049 0.724916)
			(stroke
				(width 0.1)
				(type default)
			)
			(layer "B.Fab")
		)
		(fp_line
			(start -1.1049 0.724916)
			(end -1.1049 -0.724916)
			(stroke
				(width 0.1)
				(type default)
			)
			(layer "B.Fab")
		)
		(pad "1" smd rect
			(at 0.889 0 90)
			(size 1.016 1.27)
			(layers "B.Cu" "B.Mask" "B.Paste")
			(net "PVCCD_HV_CPU0")
		)
		(pad "2" smd rect
			(at -0.889 0 90)
			(size 1.016 1.27)
			(layers "B.Cu" "B.Mask" "B.Paste")
			(net "GND")
		)
	)
	(footprint ""
		(layer "B.Cu")
		(at 164.64788 -120.106948)
		(property "Reference" "R1406"
			(at 0 0 0)
			(layer "B.SilkS")
			(hide yes)
			(effects
				(font
					(size 1.27 1.27)
				)
				(justify mirror)
			)
		)
		(property "Value" ""
			(at 0 0 0)
			(layer "B.Fab")
			(effects
				(font
					(size 1.27 1.27)
				)
				(justify mirror)
			)
		)
		(duplicate_pad_numbers_are_jumpers no)
		(fp_line
			(start -0.7874 -0.4064)
			(end -0.7874 0.4064)
			(stroke
				(width 0.1524)
				(type default)
			)
			(layer "B.SilkS")
		)
		(fp_line
			(start -0.7874 0.4064)
			(end 0.7874 0.4064)
			(stroke
				(width 0.1524)
				(type default)
			)
			(layer "B.SilkS")
		)
		(fp_line
			(start 0.7874 -0.4064)
			(end -0.7874 -0.4064)
			(stroke
				(width 0.1524)
				(type default)
			)
			(layer "B.SilkS")
		)
		(fp_line
			(start 0.7874 0.4064)
			(end 0.7874 -0.4064)
			(stroke
				(width 0.1524)
				(type default)
			)
			(layer "B.SilkS")
		)
		(fp_line
			(start -0.67945 -0.3048)
			(end -0.67945 0.3048)
			(stroke
				(width 0.1)
				(type default)
			)
			(layer "B.Fab")
		)
		(fp_line
			(start -0.67945 0.3048)
			(end -0.120396 0.3048)
			(stroke
				(width 0.1)
				(type default)
			)
			(layer "B.Fab")
		)
		(fp_line
			(start -0.12065 -0.3048)
			(end -0.67945 -0.3048)
			(stroke
				(width 0.1)
				(type default)
			)
			(layer "B.Fab")
		)
		(fp_line
			(start -0.12065 -0.2794)
			(end -0.12065 -0.3048)
			(stroke
				(width 0.1)
				(type default)
			)
			(layer "B.Fab")
		)
		(fp_line
			(start -0.120396 0.2794)
			(end 0.12065 0.2794)
			(stroke
				(width 0.1)
				(type default)
			)
			(layer "B.Fab")
		)
		(fp_line
			(start -0.120396 0.3048)
			(end -0.120396 0.2794)
			(stroke
				(width 0.1)
				(type default)
			)
			(layer "B.Fab")
		)
		(fp_line
			(start 0.12065 -0.305054)
			(end 0.12065 -0.2794)
			(stroke
				(width 0.1)
				(type default)
			)
			(layer "B.Fab")
		)
		(fp_line
			(start 0.12065 -0.2794)
			(end -0.12065 -0.2794)
			(stroke
				(width 0.1)
				(type default)
			)
			(layer "B.Fab")
		)
		(fp_line
			(start 0.12065 0.2794)
			(end 0.12065 0.3048)
			(stroke
				(width 0.1)
				(type default)
			)
			(layer "B.Fab")
		)
		(fp_line
			(start 0.12065 0.3048)
			(end 0.67945 0.3048)
			(stroke
				(width 0.1)
				(type default)
			)
			(layer "B.Fab")
		)
		(fp_line
			(start 0.67945 -0.305054)
			(end 0.12065 -0.305054)
			(stroke
				(width 0.1)
				(type default)
			)
			(layer "B.Fab")
		)
		(fp_line
			(start 0.67945 0.3048)
			(end 0.67945 -0.305054)
			(stroke
				(width 0.1)
				(type default)
			)
			(layer "B.Fab")
		)
		(pad "1" smd circle
			(at 0.40005 0 180)
			(size 0 0)
			(layers "B.Cu" "B.Mask" "B.Paste")
			(net "FM_PVCCIN_CPU1_R_EN")
		)
		(pad "2" smd circle
			(at -0.40005 0 180)
			(size 0 0)
			(layers "B.Cu" "B.Mask" "B.Paste")
			(net "GND")
		)
	)
	(footprint ""
		(layer "B.Cu")
		(at 370.539772 -184.400952 90)
		(property "Reference" "R2477"
			(at 0 0 90)
			(layer "B.SilkS")
			(hide yes)
			(effects
				(font
					(size 1.27 1.27)
				)
				(justify mirror)
			)
		)
		(property "Value" ""
			(at 0 0 90)
			(layer "B.Fab")
			(effects
				(font
					(size 1.27 1.27)
				)
				(justify mirror)
			)
		)
		(duplicate_pad_numbers_are_jumpers no)
		(fp_line
			(start 0.7874 -0.4064)
			(end -0.7874 -0.4064)
			(stroke
				(width 0.1524)
				(type default)
			)
			(layer "B.SilkS")
		)
		(fp_line
			(start -0.7874 -0.4064)
			(end -0.7874 0.4064)
			(stroke
				(width 0.1524)
				(type default)
			)
			(layer "B.SilkS")
		)
		(fp_line
			(start 0.7874 0.4064)
			(end 0.7874 -0.4064)
			(stroke
				(width 0.1524)
				(type default)
			)
			(layer "B.SilkS")
		)
		(fp_line
			(start -0.7874 0.4064)
			(end 0.7874 0.4064)
			(stroke
				(width 0.1524)
				(type default)
			)
			(layer "B.SilkS")
		)
		(fp_line
			(start 0.67945 -0.305054)
			(end 0.12065 -0.305054)
			(stroke
				(width 0.1)
				(type default)
			)
			(layer "B.Fab")
		)
		(fp_line
			(start 0.12065 -0.305054)
			(end 0.12065 -0.2794)
			(stroke
				(width 0.1)
				(type default)
			)
			(layer "B.Fab")
		)
		(fp_line
			(start -0.12065 -0.3048)
			(end -0.67945 -0.3048)
			(stroke
				(width 0.1)
				(type default)
			)
			(layer "B.Fab")
		)
		(fp_line
			(start -0.67945 -0.3048)
			(end -0.67945 0.3048)
			(stroke
				(width 0.1)
				(type default)
			)
			(layer "B.Fab")
		)
		(fp_line
			(start 0.12065 -0.2794)
			(end -0.12065 -0.2794)
			(stroke
				(width 0.1)
				(type default)
			)
			(layer "B.Fab")
		)
		(fp_line
			(start -0.12065 -0.2794)
			(end -0.12065 -0.3048)
			(stroke
				(width 0.1)
				(type default)
			)
			(layer "B.Fab")
		)
		(fp_line
			(start 0.12065 0.2794)
			(end 0.12065 0.3048)
			(stroke
				(width 0.1)
				(type default)
			)
			(layer "B.Fab")
		)
		(fp_line
			(start -0.120396 0.2794)
			(end 0.12065 0.2794)
			(stroke
				(width 0.1)
				(type default)
			)
			(layer "B.Fab")
		)
		(fp_line
			(start 0.67945 0.3048)
			(end 0.67945 -0.305054)
			(stroke
				(width 0.1)
				(type default)
			)
			(layer "B.Fab")
		)
		(fp_line
			(start 0.12065 0.3048)
			(end 0.67945 0.3048)
			(stroke
				(width 0.1)
				(type default)
			)
			(layer "B.Fab")
		)
		(fp_line
			(start -0.120396 0.3048)
			(end -0.120396 0.2794)
			(stroke
				(width 0.1)
				(type default)
			)
			(layer "B.Fab")
		)
		(fp_line
			(start -0.67945 0.3048)
			(end -0.120396 0.3048)
			(stroke
				(width 0.1)
				(type default)
			)
			(layer "B.Fab")
		)
		(pad "1" smd circle
			(at 0.40005 0 270)
			(size 0 0)
			(layers "B.Cu" "B.Mask" "B.Paste")
			(net "SMB_PEHPCPU0_LVC3_SCL_R0")
		)
		(pad "2" smd circle
			(at -0.40005 0 270)
			(size 0 0)
			(layers "B.Cu" "B.Mask" "B.Paste")
			(net "SMB_PEHPCPU0_LVC3_SCL")
		)
	)
	(footprint ""
		(layer "B.Cu")
		(at 49.936146 -319.268856 180)
		(property "Reference" "R896"
			(at 0 0 0)
			(layer "B.SilkS")
			(hide yes)
			(effects
				(font
					(size 1.27 1.27)
				)
				(justify mirror)
			)
		)
		(property "Value" ""
			(at 0 0 0)
			(layer "B.Fab")
			(effects
				(font
					(size 1.27 1.27)
				)
				(justify mirror)
			)
		)
		(duplicate_pad_numbers_are_jumpers no)
		(fp_line
			(start 0.7874 0.4064)
			(end 0.7874 -0.4064)
			(stroke
				(width 0.1524)
				(type default)
			)
			(layer "B.SilkS")
		)
		(fp_line
			(start 0.7874 -0.4064)
			(end -0.7874 -0.4064)
			(stroke
				(width 0.1524)
				(type default)
			)
			(layer "B.SilkS")
		)
		(fp_line
			(start -0.7874 0.4064)
			(end 0.7874 0.4064)
			(stroke
				(width 0.1524)
				(type default)
			)
			(layer "B.SilkS")
		)
		(fp_line
			(start -0.7874 -0.4064)
			(end -0.7874 0.4064)
			(stroke
				(width 0.1524)
				(type default)
			)
			(layer "B.SilkS")
		)
		(fp_line
			(start 0.67945 0.3048)
			(end 0.67945 -0.305054)
			(stroke
				(width 0.1)
				(type default)
			)
			(layer "B.Fab")
		)
		(fp_line
			(start 0.67945 -0.305054)
			(end 0.12065 -0.305054)
			(stroke
				(width 0.1)
				(type default)
			)
			(layer "B.Fab")
		)
		(fp_line
			(start 0.12065 0.3048)
			(end 0.67945 0.3048)
			(stroke
				(width 0.1)
				(type default)
			)
			(layer "B.Fab")
		)
		(fp_line
			(start 0.12065 0.2794)
			(end 0.12065 0.3048)
			(stroke
				(width 0.1)
				(type default)
			)
			(layer "B.Fab")
		)
		(fp_line
			(start 0.12065 -0.2794)
			(end -0.12065 -0.2794)
			(stroke
				(width 0.1)
				(type default)
			)
			(layer "B.Fab")
		)
		(fp_line
			(start 0.12065 -0.305054)
			(end 0.12065 -0.2794)
			(stroke
				(width 0.1)
				(type default)
			)
			(layer "B.Fab")
		)
		(fp_line
			(start -0.120396 0.3048)
			(end -0.120396 0.2794)
			(stroke
				(width 0.1)
				(type default)
			)
			(layer "B.Fab")
		)
		(fp_line
			(start -0.120396 0.2794)
			(end 0.12065 0.2794)
			(stroke
				(width 0.1)
				(type default)
			)
			(layer "B.Fab")
		)
		(fp_line
			(start -0.12065 -0.2794)
			(end -0.12065 -0.3048)
			(stroke
				(width 0.1)
				(type default)
			)
			(layer "B.Fab")
		)
		(fp_line
			(start -0.12065 -0.3048)
			(end -0.67945 -0.3048)
			(stroke
				(width 0.1)
				(type default)
			)
			(layer "B.Fab")
		)
		(fp_line
			(start -0.67945 0.3048)
			(end -0.120396 0.3048)
			(stroke
				(width 0.1)
				(type default)
			)
			(layer "B.Fab")
		)
		(fp_line
			(start -0.67945 -0.3048)
			(end -0.67945 0.3048)
			(stroke
				(width 0.1)
				(type default)
			)
			(layer "B.Fab")
		)
		(pad "1" smd circle
			(at 0.40005 0)
			(size 0 0)
			(layers "B.Cu" "B.Mask" "B.Paste")
			(net "PWRGD_CHB_CPU1_DIMM2")
		)
		(pad "2" smd circle
			(at -0.40005 0)
			(size 0 0)
			(layers "B.Cu" "B.Mask" "B.Paste")
			(net "PWRGD_FAIL_CPU1_AB")
		)
	)
)
